FILE_TYPE = CONNECTIVITY;
{Allegro Design Entry HDL 17.2-2016 S081 (4005846) 1/11/2022}
"PAGE_NUMBER" = 13;
0"NC";
1"M_D_CPU0_SA_DQ<31:0>";
2"M_D_CPU0_SB_DQ<31:0>";
3"M_D_CPU0_SA_CB<7:0>";
4"M_D_CPU0_SB_CB<7:0>";
5"M_D_CPU0_SA_DQS_DP<9:0>";
6"M_D_CPU0_SB_DQS_DP<9:0>";
7"M_D_CPU0_SA_CA<6:0>";
8"M_D_CPU0_SB_CA<6:0>";
9"M_D_CPU0_SA_DQS_DN<9:0>";
10"M_D_CPU0_SB_DQS_DN<9:0>";
11"M_D_CPU0_ALERT_N";
12"TP_M_D_CPU0_SA_TEST39D";
13"M_D_CPU0_ALERT_R_N";
14"M_D_CPU0_CLK_DP<0>";
15"M_D_CPU0_CLK_DN<0>";
16"M_D_CPU0_SA_CS_N<0>";
17"M_D_CPU0_SA_CS_N<1>";
18"M_D_CPU0_SA_RSP<0>";
19"M_D_CPU0_SA_PAR";
20"M_D_CPU0_SB_CS_N<0>";
21"M_D_CPU0_SB_CS_N<1>";
22"M_D_CPU0_SB_RSP<0>";
23"M_D_CPU0_SB_PAR";
24"M_D_CPU0_RESET_N";
25"M_D_CPU0_SB_DQS_DP<9>";
26"M_D_CPU0_SB_CA<3>";
27"M_D_CPU0_SB_CA<6>";
28"M_D_CPU0_SA_CA<6>";
29"M_D_CPU0_SB_CA<5>";
30"M_D_CPU0_SA_CA<5>";
31"M_D_CPU0_SB_CA<4>";
32"M_D_CPU0_SA_CA<4>";
33"M_D_CPU0_SB_DQS_DN<9>";
34"M_D_CPU0_SA_CA<3>";
35"M_D_CPU0_SB_CA<2>";
36"M_D_CPU0_SA_CA<2>";
37"M_D_CPU0_SB_CA<1>";
38"M_D_CPU0_SA_CA<1>";
39"M_D_CPU0_SB_CA<0>";
40"M_D_CPU0_SA_CA<0>";
41"M_D_CPU0_SB_DQS_DP<8>";
42"M_D_CPU0_SB_DQS_DP<7>";
43"M_D_CPU0_SB_DQS_DP<6>";
44"M_D_CPU0_SB_DQS_DP<5>";
45"M_D_CPU0_SB_DQS_DP<4>";
46"M_D_CPU0_SB_DQS_DN<8>";
47"M_D_CPU0_SB_DQS_DP<3>";
48"M_D_CPU0_SB_DQS_DN<7>";
49"M_D_CPU0_SB_DQS_DP<2>";
50"M_D_CPU0_SB_DQS_DN<6>";
51"M_D_CPU0_SB_DQS_DP<1>";
52"M_D_CPU0_SB_DQS_DN<5>";
53"M_D_CPU0_SB_DQS_DP<0>";
54"M_D_CPU0_SB_DQS_DN<4>";
55"M_D_CPU0_SA_DQS_DN<9>";
56"M_D_CPU0_SB_DQS_DN<3>";
57"M_D_CPU0_SB_DQS_DN<2>";
58"M_D_CPU0_SB_DQS_DN<1>";
59"M_D_CPU0_SB_DQS_DN<0>";
60"M_D_CPU0_SA_DQS_DP<0>";
61"M_D_CPU0_SA_DQS_DN<4>";
62"M_D_CPU0_SA_DQS_DN<3>";
63"M_D_CPU0_SA_DQS_DN<2>";
64"M_D_CPU0_SA_DQS_DN<1>";
65"M_D_CPU0_SA_DQS_DN<0>";
66"M_D_CPU0_SA_DQS_DP<9>";
67"M_D_CPU0_SA_DQS_DP<8>";
68"M_D_CPU0_SA_DQS_DP<7>";
69"M_D_CPU0_SA_DQS_DP<6>";
70"M_D_CPU0_SA_DQS_DP<5>";
71"M_D_CPU0_SA_DQS_DP<4>";
72"M_D_CPU0_SA_DQS_DN<8>";
73"M_D_CPU0_SA_DQS_DP<3>";
74"M_D_CPU0_SA_DQS_DN<7>";
75"M_D_CPU0_SA_DQS_DP<2>";
76"M_D_CPU0_SA_DQS_DN<6>";
77"M_D_CPU0_SA_DQS_DP<1>";
78"M_D_CPU0_SA_DQS_DN<5>";
79"M_D_CPU0_SB_CB<2>";
80"M_D_CPU0_SB_CB<1>";
81"M_D_CPU0_SB_CB<0>";
82"M_D_CPU0_SB_CB<7>";
83"M_D_CPU0_SB_CB<6>";
84"M_D_CPU0_SB_CB<5>";
85"M_D_CPU0_SB_CB<4>";
86"M_D_CPU0_SB_CB<3>";
87"M_D_CPU0_SB_DQ<22>";
88"M_D_CPU0_SA_CB<7>";
89"M_D_CPU0_SA_CB<6>";
90"M_D_CPU0_SB_DQ<31>";
91"M_D_CPU0_SA_CB<5>";
92"M_D_CPU0_SB_DQ<30>";
93"M_D_CPU0_SA_CB<4>";
94"M_D_CPU0_SA_CB<3>";
95"M_D_CPU0_SA_CB<2>";
96"M_D_CPU0_SA_CB<1>";
97"M_D_CPU0_SA_CB<0>";
98"M_D_CPU0_SB_DQ<29>";
99"M_D_CPU0_SB_DQ<28>";
100"M_D_CPU0_SB_DQ<27>";
101"M_D_CPU0_SB_DQ<26>";
102"M_D_CPU0_SB_DQ<25>";
103"M_D_CPU0_SB_DQ<24>";
104"M_D_CPU0_SB_DQ<23>";
105"M_D_CPU0_SB_DQ<11>";
106"M_D_CPU0_SB_DQ<10>";
107"M_D_CPU0_SB_DQ<21>";
108"M_D_CPU0_SB_DQ<20>";
109"M_D_CPU0_SB_DQ<9>";
110"M_D_CPU0_SB_DQ<19>";
111"M_D_CPU0_SB_DQ<8>";
112"M_D_CPU0_SB_DQ<18>";
113"M_D_CPU0_SB_DQ<7>";
114"M_D_CPU0_SB_DQ<17>";
115"M_D_CPU0_SB_DQ<6>";
116"M_D_CPU0_SB_DQ<16>";
117"M_D_CPU0_SB_DQ<5>";
118"M_D_CPU0_SB_DQ<15>";
119"M_D_CPU0_SB_DQ<4>";
120"M_D_CPU0_SB_DQ<14>";
121"M_D_CPU0_SB_DQ<3>";
122"M_D_CPU0_SB_DQ<13>";
123"M_D_CPU0_SB_DQ<12>";
124"M_D_CPU0_SA_DQ<17>";
125"M_D_CPU0_SA_DQ<28>";
126"M_D_CPU0_SB_DQ<1>";
127"M_D_CPU0_SA_DQ<27>";
128"M_D_CPU0_SB_DQ<0>";
129"M_D_CPU0_SA_DQ<26>";
130"M_D_CPU0_SA_DQ<25>";
131"M_D_CPU0_SA_DQ<24>";
132"M_D_CPU0_SA_DQ<23>";
133"M_D_CPU0_SA_DQ<22>";
134"M_D_CPU0_SA_DQ<21>";
135"M_D_CPU0_SA_DQ<20>";
136"M_D_CPU0_SA_DQ<31>";
137"M_D_CPU0_SA_DQ<30>";
138"M_D_CPU0_SA_DQ<19>";
139"M_D_CPU0_SA_DQ<18>";
140"M_D_CPU0_SA_DQ<29>";
141"M_D_CPU0_SB_DQ<2>";
142"M_D_CPU0_SA_DQ<2>";
143"M_D_CPU0_SA_DQ<1>";
144"M_D_CPU0_SA_DQ<16>";
145"M_D_CPU0_SA_DQ<0>";
146"M_D_CPU0_SA_DQ<15>";
147"M_D_CPU0_SA_DQ<14>";
148"M_D_CPU0_SA_DQ<13>";
149"M_D_CPU0_SA_DQ<12>";
150"M_D_CPU0_SA_DQ<11>";
151"M_D_CPU0_SA_DQ<10>";
152"M_D_CPU0_SA_DQ<9>";
153"M_D_CPU0_SA_DQ<8>";
154"M_D_CPU0_SA_DQ<7>";
155"M_D_CPU0_SA_DQ<6>";
156"M_D_CPU0_SA_DQ<5>";
157"M_D_CPU0_SA_DQ<4>";
158"M_D_CPU0_SA_DQ<3>";
%"GENOA_SP5"
"4","(-4600,3650)","0","pure_quanta","I159";
;
LOCATION"U25"
$SEC"4"
CDS_SEC"4"
PART_TYPE"SMLF"
MATERIAL"IO"
VALUE"SOCKET6096_13568-001"
PART_NUMBER"DGA^6000030"
CDS_LIB"pure_quanta"
CDS_LMAN_SYM_OUTLINE"-650,2525,650,-2525"
NEEDS_NO_SIZE"TRUE";
"TEST39D"
$PN"BF58"12;
"MD1_CLK_L"
$PN"BG60"0;
"MD1_CLK_H"
$PN"BF60"0;
"MD0_CLK_L"
$PN"BD60"15;
"MD0_CLK_H"
$PN"BC60"14;
"MDB_DQS_H9"
$PN"BV60"25;
"MDB_CA3"
$PN"BJ60"26;
"MDB_PAR"
$PN"BL60"23;
"MDA_PAR"
$PN"BC59"19;
"MDA1_RSP_L"
$PN"BP58"0;
"MDA_DATA2"
$PN"F60"142;
"MDA_DATA17"
$PN"V58"124;
"MDA_DATA28"
$PN"AG60"125;
"MDA_DQS_H0"
$PN"G60"60;
"MDA_DQS_L4"
$PN"AM60"61;
"MDB_CHECK2"
$PN"CA60"79;
"MDB_DATA1"
$PN"CC59"126;
"MDB_DATA11"
$PN"CK58"105;
"MDB_DATA22"
$PN"CW60"87;
"MDA0_RSP_L"
$PN"BN59"18;
"MDA_CHECK7"
$PN"AR59"88;
"MDA_DATA1"
$PN"F58"143;
"MDA_DATA16"
$PN"U60"144;
"MDA_DATA27"
$PN"AE59"127;
"MDA_DQS_L3"
$PN"AF60"62;
"MDB_CHECK1"
$PN"CA59"80;
"MDB_DATA0"
$PN"CB60"128;
"MDB_DATA10"
$PN"CJ60"106;
"MDB_DATA21"
$PN"CW59"107;
"MDA_CHECK6"
$PN"AP60"89;
"MDA_DATA0"
$PN"E60"145;
"MDA_DATA15"
$PN"U59"146;
"MDA_DATA26"
$PN"AD60"129;
"MDA_DQS_L2"
$PN"Y60"63;
"MDB1_CS_L1"
$PN"BM60"0;
"MDB_CHECK0"
$PN"BY60"81;
"MDB_DATA20"
$PN"CV60"108;
"MDB_DATA31"
$PN"DF60"90;
"MDA_CHECK5"
$PN"AP58"91;
"MDA_DATA14"
$PN"T60"147;
"MDA_DATA25"
$PN"AD58"130;
"MDA_DQS_L1"
$PN"P60"64;
"MDB0_CS_L1"
$PN"BN60"21;
"MDB1_CS_L0"
$PN"BL59"0;
"MDB_CA6"
$PN"BK60"27;
"MDB_DATA30"
$PN"DE60"92;
"MDB_DQS_H8"
$PN"DD58"41;
"MDA_CA6"
$PN"BB58"28;
"MDA_CHECK4"
$PN"AN60"93;
"MDA_DATA13"
$PN"T58"148;
"MDA_DATA24"
$PN"AC60"131;
"MDA_DQS_L0"
$PN"H60"65;
"MDB0_CS_L0"
$PN"BM58"20;
"MDB_CA5"
$PN"BK58"29;
"MDB_DQS_H7"
$PN"CV58"42;
"MDA_CA5"
$PN"BB60"30;
"MDA_CHECK3"
$PN"AL59"94;
"MDA_DATA12"
$PN"R60"149;
"MDA_DATA23"
$PN"AC59"132;
"MDB_CA4"
$PN"BJ59"31;
"MDB_DQS_H6"
$PN"CM58"43;
"MDA_CA4"
$PN"BA60"32;
"MDA_CHECK2"
$PN"AK60"95;
"MDA_DATA11"
$PN"N59"150;
"MDA_DATA22"
$PN"AB60"133;
"MDB_DQS_H5"
$PN"CF58"44;
"MDB_DQS_L9"
$PN"BW60"33;
"MDA_CA3"
$PN"BA59"34;
"MDA_CHECK1"
$PN"AK58"96;
"MDA_DATA10"
$PN"M60"151;
"MDA_DATA21"
$PN"AB58"134;
"MDB_CA2"
$PN"BH60"35;
"MDB_DQS_H4"
$PN"BY58"45;
"MDB_DQS_L8"
$PN"DC59"46;
"MDA1_CS_L1"
$PN"AV58"0;
"MDA_CA2"
$PN"AY58"36;
"MDA_CHECK0"
$PN"AJ60"97;
"MDA_DATA20"
$PN"AA60"135;
"MDA_DATA31"
$PN"AJ59"136;
"MDA_DQS_H9"
$PN"AN59"66;
"MDB_CA1"
$PN"BH58"37;
"MDB_DQS_H3"
$PN"DB60"47;
"MDB_DQS_L7"
$PN"CU59"48;
"MDA0_CS_L1"
$PN"AW59"17;
"MDA1_CS_L0"
$PN"AU60"0;
"MDA_CA1"
$PN"AY60"38;
"MDA_DATA30"
$PN"AH60"137;
"MDA_DQS_H8"
$PN"AG59"67;
"MDB_CA0"
$PN"BG59"39;
"MDB_DATA9"
$PN"CJ59"109;
"MDB_DATA19"
$PN"CT58"110;
"MDB_DQS_H2"
$PN"CT60"49;
"MDB_DQS_L6"
$PN"CL59"50;
"MDA0_CS_L0"
$PN"AV60"16;
"MDA_CA0"
$PN"AW60"40;
"MDA_DATA9"
$PN"M58"152;
"MDA_DQS_H7"
$PN"AA59"68;
"MDB_DATA8"
$PN"CH60"111;
"MDB_DATA18"
$PN"CR60"112;
"MDB_DATA29"
$PN"DE59"98;
"MDB_DQS_H1"
$PN"CK60"51;
"MDB_DQS_L5"
$PN"CE59"52;
"MDA_DATA8"
$PN"L60"153;
"MDA_DQS_H6"
$PN"R59"69;
"MDB1_RSP_L"
$PN"BR60"0;
"MDB_DATA7"
$PN"CH58"113;
"MDB_DATA17"
$PN"CR59"114;
"MDB_DATA28"
$PN"DD60"99;
"MDB_DQS_H0"
$PN"CD60"53;
"MDB_DQS_L4"
$PN"BW59"54;
"MDA_DATA7"
$PN"L59"154;
"MDA_DQS_H5"
$PN"J59"70;
"MDA_DQS_L9"
$PN"AM58"55;
"MDB0_RSP_L"
$PN"BP60"22;
"MDB_CHECK7"
$PN"BV58"82;
"MDB_DATA6"
$PN"CG60"115;
"MDB_DATA16"
$PN"CP60"116;
"MDB_DATA27"
$PN"DB58"100;
"MDB_DQS_L3"
$PN"DC60"56;
"MDA_DATA6"
$PN"K60"155;
"MDA_DQS_H4"
$PN"AL60"71;
"MDA_DQS_L8"
$PN"AF58"72;
"MDB_CHECK6"
$PN"BU60"83;
"MDB_DATA5"
$PN"CG59"117;
"MDB_DATA15"
$PN"CP58"118;
"MDB_DATA26"
$PN"DA60"101;
"MDB_DQS_L2"
$PN"CU60"57;
"MDA_DATA5"
$PN"K58"156;
"MDA_DQS_H3"
$PN"AE60"73;
"MDA_DQS_L7"
$PN"Y58"74;
"MDB_CHECK5"
$PN"BU59"84;
"MDB_DATA4"
$PN"CF60"119;
"MDB_DATA14"
$PN"CN60"120;
"MDB_DATA25"
$PN"DA59"102;
"MDB_DQS_L1"
$PN"CL60"58;
"MDA_DATA4"
$PN"J60"157;
"MDA_DATA19"
$PN"W59"138;
"MDA_DQS_H2"
$PN"W60"75;
"MDA_DQS_L6"
$PN"P58"76;
"MDB_CHECK4"
$PN"BT60"85;
"MDB_DATA3"
$PN"CD58"121;
"MDB_DATA13"
$PN"CN59"122;
"MDB_DATA24"
$PN"CY60"103;
"MDB_DQS_L0"
$PN"CE60"59;
"MDA_DATA3"
$PN"G59"158;
"MDA_DATA18"
$PN"V60"139;
"MDA_DATA29"
$PN"AH58"140;
"MDA_DQS_H1"
$PN"N60"77;
"MDA_DQS_L5"
$PN"H58"78;
"MDB_CHECK3"
$PN"CB58"86;
"MDB_DATA2"
$PN"CC60"141;
"MDB_DATA12"
$PN"CM60"123;
"MDB_DATA23"
$PN"CY58"104;
"MD_RESET_L"
$PN"AU59"24;
"MD_ALERT_L"
$PN"AT58"13;
%"TAP"
"1","(-3325,5925)","0","mstr_standard","I162";
;
CDS_LIB"mstr_standard"
BODY_TYPE"PLUMBING"
HDL_TAP"TRUE";
"B \NAC \NWC"1;
"S \NAC"
BN"2"142;
%"TAP"
"1","(-3325,6025)","0","mstr_standard","I163";
;
CDS_LIB"mstr_standard"
BODY_TYPE"PLUMBING"
HDL_TAP"TRUE";
"B \NAC \NWC"1;
"S \NAC"
BN"0"145;
%"TAP"
"1","(-3325,5975)","0","mstr_standard","I164";
;
CDS_LIB"mstr_standard"
BODY_TYPE"PLUMBING"
HDL_TAP"TRUE";
"B \NAC \NWC"1;
"S \NAC"
BN"1"143;
%"TAP"
"1","(-3325,5775)","0","mstr_standard","I165";
;
CDS_LIB"mstr_standard"
BODY_TYPE"PLUMBING"
HDL_TAP"TRUE";
"B \NAC \NWC"1;
"S \NAC"
BN"5"156;
%"TAP"
"1","(-3325,5875)","0","mstr_standard","I166";
;
CDS_LIB"mstr_standard"
BODY_TYPE"PLUMBING"
HDL_TAP"TRUE";
"B \NAC \NWC"1;
"S \NAC"
BN"3"158;
%"TAP"
"1","(-3325,5825)","0","mstr_standard","I167";
;
CDS_LIB"mstr_standard"
BODY_TYPE"PLUMBING"
HDL_TAP"TRUE";
"B \NAC \NWC"1;
"S \NAC"
BN"4"157;
%"TAP"
"1","(-3325,5725)","0","mstr_standard","I168";
;
CDS_LIB"mstr_standard"
BODY_TYPE"PLUMBING"
HDL_TAP"TRUE";
"B \NAC \NWC"1;
"S \NAC"
BN"6"155;
%"TAP"
"1","(-3325,5675)","0","mstr_standard","I169";
;
CDS_LIB"mstr_standard"
BODY_TYPE"PLUMBING"
HDL_TAP"TRUE";
"B \NAC \NWC"1;
"S \NAC"
BN"7"154;
%"TAP"
"1","(-3325,5525)","0","mstr_standard","I170";
;
CDS_LIB"mstr_standard"
BODY_TYPE"PLUMBING"
HDL_TAP"TRUE";
"B \NAC \NWC"1;
"S \NAC"
BN"9"152;
%"TAP"
"1","(-3325,5575)","0","mstr_standard","I171";
;
CDS_LIB"mstr_standard"
BODY_TYPE"PLUMBING"
HDL_TAP"TRUE";
"B \NAC \NWC"1;
"S \NAC"
BN"8"153;
%"TAP"
"1","(-3325,5475)","0","mstr_standard","I172";
;
CDS_LIB"mstr_standard"
BODY_TYPE"PLUMBING"
HDL_TAP"TRUE";
"B \NAC \NWC"1;
"S \NAC"
BN"10"151;
%"TAP"
"1","(-3325,5425)","0","mstr_standard","I173";
;
CDS_LIB"mstr_standard"
BODY_TYPE"PLUMBING"
HDL_TAP"TRUE";
"B \NAC \NWC"1;
"S \NAC"
BN"11"150;
%"TAP"
"1","(-3325,5275)","0","mstr_standard","I174";
;
CDS_LIB"mstr_standard"
BODY_TYPE"PLUMBING"
HDL_TAP"TRUE";
"B \NAC \NWC"1;
"S \NAC"
BN"14"147;
%"TAP"
"1","(-3325,5375)","0","mstr_standard","I175";
;
CDS_LIB"mstr_standard"
BODY_TYPE"PLUMBING"
HDL_TAP"TRUE";
"B \NAC \NWC"1;
"S \NAC"
BN"12"149;
%"TAP"
"1","(-3325,5325)","0","mstr_standard","I176";
;
CDS_LIB"mstr_standard"
BODY_TYPE"PLUMBING"
HDL_TAP"TRUE";
"B \NAC \NWC"1;
"S \NAC"
BN"13"148;
%"TAP"
"1","(-3325,5225)","0","mstr_standard","I177";
;
CDS_LIB"mstr_standard"
BODY_TYPE"PLUMBING"
HDL_TAP"TRUE";
"B \NAC \NWC"1;
"S \NAC"
BN"15"146;
%"TAP"
"1","(-3325,5125)","0","mstr_standard","I178";
;
CDS_LIB"mstr_standard"
BODY_TYPE"PLUMBING"
HDL_TAP"TRUE";
"B \NAC \NWC"1;
"S \NAC"
BN"16"144;
%"TAP"
"1","(-3325,5025)","0","mstr_standard","I179";
;
CDS_LIB"mstr_standard"
BODY_TYPE"PLUMBING"
HDL_TAP"TRUE";
"B \NAC \NWC"1;
"S \NAC"
BN"18"139;
%"TAP"
"1","(-3325,5075)","0","mstr_standard","I180";
;
CDS_LIB"mstr_standard"
BODY_TYPE"PLUMBING"
HDL_TAP"TRUE";
"B \NAC \NWC"1;
"S \NAC"
BN"17"124;
%"TAP"
"1","(-3325,4975)","0","mstr_standard","I181";
;
CDS_LIB"mstr_standard"
BODY_TYPE"PLUMBING"
HDL_TAP"TRUE";
"B \NAC \NWC"1;
"S \NAC"
BN"19"138;
%"TAP"
"1","(-3325,4875)","0","mstr_standard","I182";
;
CDS_LIB"mstr_standard"
BODY_TYPE"PLUMBING"
HDL_TAP"TRUE";
"B \NAC \NWC"1;
"S \NAC"
BN"21"134;
%"TAP"
"1","(-3325,4925)","0","mstr_standard","I183";
;
CDS_LIB"mstr_standard"
BODY_TYPE"PLUMBING"
HDL_TAP"TRUE";
"B \NAC \NWC"1;
"S \NAC"
BN"20"135;
%"TAP"
"1","(-3325,4675)","0","mstr_standard","I184";
;
CDS_LIB"mstr_standard"
BODY_TYPE"PLUMBING"
HDL_TAP"TRUE";
"B \NAC \NWC"1;
"S \NAC"
BN"24"131;
%"TAP"
"1","(-3325,4625)","0","mstr_standard","I185";
;
CDS_LIB"mstr_standard"
BODY_TYPE"PLUMBING"
HDL_TAP"TRUE";
"B \NAC \NWC"1;
"S \NAC"
BN"25"130;
%"TAP"
"1","(-3325,4775)","0","mstr_standard","I186";
;
CDS_LIB"mstr_standard"
BODY_TYPE"PLUMBING"
HDL_TAP"TRUE";
"B \NAC \NWC"1;
"S \NAC"
BN"23"132;
%"TAP"
"1","(-3325,4825)","0","mstr_standard","I187";
;
CDS_LIB"mstr_standard"
BODY_TYPE"PLUMBING"
HDL_TAP"TRUE";
"B \NAC \NWC"1;
"S \NAC"
BN"22"133;
%"TAP"
"1","(-3325,4575)","0","mstr_standard","I188";
;
CDS_LIB"mstr_standard"
BODY_TYPE"PLUMBING"
HDL_TAP"TRUE";
"B \NAC \NWC"1;
"S \NAC"
BN"26"129;
%"TAP"
"1","(-3325,4525)","0","mstr_standard","I189";
;
CDS_LIB"mstr_standard"
BODY_TYPE"PLUMBING"
HDL_TAP"TRUE";
"B \NAC \NWC"1;
"S \NAC"
BN"27"127;
%"TAP"
"1","(-3325,4475)","0","mstr_standard","I190";
;
CDS_LIB"mstr_standard"
BODY_TYPE"PLUMBING"
HDL_TAP"TRUE";
"B \NAC \NWC"1;
"S \NAC"
BN"28"125;
%"TAP"
"1","(-3325,4375)","0","mstr_standard","I191";
;
CDS_LIB"mstr_standard"
BODY_TYPE"PLUMBING"
HDL_TAP"TRUE";
"B \NAC \NWC"1;
"S \NAC"
BN"30"137;
%"TAP"
"1","(-3325,4425)","0","mstr_standard","I192";
;
CDS_LIB"mstr_standard"
BODY_TYPE"PLUMBING"
HDL_TAP"TRUE";
"B \NAC \NWC"1;
"S \NAC"
BN"29"140;
%"TAP"
"1","(-3325,4125)","0","mstr_standard","I193";
;
CDS_LIB"mstr_standard"
BODY_TYPE"PLUMBING"
HDL_TAP"TRUE";
"B \NAC \NWC"2;
"S \NAC"
BN"2"141;
%"TAP"
"1","(-3325,4225)","0","mstr_standard","I194";
;
CDS_LIB"mstr_standard"
BODY_TYPE"PLUMBING"
HDL_TAP"TRUE";
"B \NAC \NWC"2;
"S \NAC"
BN"0"128;
%"TAP"
"1","(-3325,4325)","0","mstr_standard","I195";
;
CDS_LIB"mstr_standard"
BODY_TYPE"PLUMBING"
HDL_TAP"TRUE";
"B \NAC \NWC"1;
"S \NAC"
BN"31"136;
%"TAP"
"1","(-3325,4175)","0","mstr_standard","I196";
;
CDS_LIB"mstr_standard"
BODY_TYPE"PLUMBING"
HDL_TAP"TRUE";
"B \NAC \NWC"2;
"S \NAC"
BN"1"126;
%"TAP"
"1","(-3325,3975)","0","mstr_standard","I198";
;
CDS_LIB"mstr_standard"
BODY_TYPE"PLUMBING"
HDL_TAP"TRUE";
"B \NAC \NWC"2;
"S \NAC"
BN"5"117;
%"TAP"
"1","(-3325,4075)","0","mstr_standard","I199";
;
CDS_LIB"mstr_standard"
BODY_TYPE"PLUMBING"
HDL_TAP"TRUE";
"B \NAC \NWC"2;
"S \NAC"
BN"3"121;
%"TAP"
"1","(-3325,4025)","0","mstr_standard","I200";
;
CDS_LIB"mstr_standard"
BODY_TYPE"PLUMBING"
HDL_TAP"TRUE";
"B \NAC \NWC"2;
"S \NAC"
BN"4"119;
%"TAP"
"1","(-3325,3925)","0","mstr_standard","I201";
;
CDS_LIB"mstr_standard"
BODY_TYPE"PLUMBING"
HDL_TAP"TRUE";
"B \NAC \NWC"2;
"S \NAC"
BN"6"115;
%"TAP"
"1","(-3325,3875)","0","mstr_standard","I202";
;
CDS_LIB"mstr_standard"
BODY_TYPE"PLUMBING"
HDL_TAP"TRUE";
"B \NAC \NWC"2;
"S \NAC"
BN"7"113;
%"TAP"
"1","(-3325,3775)","0","mstr_standard","I203";
;
CDS_LIB"mstr_standard"
BODY_TYPE"PLUMBING"
HDL_TAP"TRUE";
"B \NAC \NWC"2;
"S \NAC"
BN"8"111;
%"TAP"
"1","(-3325,3725)","0","mstr_standard","I204";
;
CDS_LIB"mstr_standard"
BODY_TYPE"PLUMBING"
HDL_TAP"TRUE";
"B \NAC \NWC"2;
"S \NAC"
BN"9"109;
%"TAP"
"1","(-3325,3675)","0","mstr_standard","I205";
;
CDS_LIB"mstr_standard"
BODY_TYPE"PLUMBING"
HDL_TAP"TRUE";
"B \NAC \NWC"2;
"S \NAC"
BN"10"106;
%"TAP"
"1","(-3325,3625)","0","mstr_standard","I206";
;
CDS_LIB"mstr_standard"
BODY_TYPE"PLUMBING"
HDL_TAP"TRUE";
"B \NAC \NWC"2;
"S \NAC"
BN"11"105;
%"TAP"
"1","(-3325,3475)","0","mstr_standard","I207";
;
CDS_LIB"mstr_standard"
BODY_TYPE"PLUMBING"
HDL_TAP"TRUE";
"B \NAC \NWC"2;
"S \NAC"
BN"14"120;
%"TAP"
"1","(-3325,3575)","0","mstr_standard","I208";
;
CDS_LIB"mstr_standard"
BODY_TYPE"PLUMBING"
HDL_TAP"TRUE";
"B \NAC \NWC"2;
"S \NAC"
BN"12"123;
%"TAP"
"1","(-3325,3525)","0","mstr_standard","I209";
;
CDS_LIB"mstr_standard"
BODY_TYPE"PLUMBING"
HDL_TAP"TRUE";
"B \NAC \NWC"2;
"S \NAC"
BN"13"122;
%"TAP"
"1","(-3325,3425)","0","mstr_standard","I210";
;
CDS_LIB"mstr_standard"
BODY_TYPE"PLUMBING"
HDL_TAP"TRUE";
"B \NAC \NWC"2;
"S \NAC"
BN"15"118;
%"TAP"
"1","(-3325,3225)","0","mstr_standard","I211";
;
CDS_LIB"mstr_standard"
BODY_TYPE"PLUMBING"
HDL_TAP"TRUE";
"B \NAC \NWC"2;
"S \NAC"
BN"18"112;
%"TAP"
"1","(-3325,3275)","0","mstr_standard","I212";
;
CDS_LIB"mstr_standard"
BODY_TYPE"PLUMBING"
HDL_TAP"TRUE";
"B \NAC \NWC"2;
"S \NAC"
BN"17"114;
%"TAP"
"1","(-3325,3325)","0","mstr_standard","I213";
;
CDS_LIB"mstr_standard"
BODY_TYPE"PLUMBING"
HDL_TAP"TRUE";
"B \NAC \NWC"2;
"S \NAC"
BN"16"116;
%"TAP"
"1","(-3325,3075)","0","mstr_standard","I214";
;
CDS_LIB"mstr_standard"
BODY_TYPE"PLUMBING"
HDL_TAP"TRUE";
"B \NAC \NWC"2;
"S \NAC"
BN"21"107;
%"TAP"
"1","(-3325,3175)","0","mstr_standard","I215";
;
CDS_LIB"mstr_standard"
BODY_TYPE"PLUMBING"
HDL_TAP"TRUE";
"B \NAC \NWC"2;
"S \NAC"
BN"19"110;
%"TAP"
"1","(-3325,3125)","0","mstr_standard","I216";
;
CDS_LIB"mstr_standard"
BODY_TYPE"PLUMBING"
HDL_TAP"TRUE";
"B \NAC \NWC"2;
"S \NAC"
BN"20"108;
%"TAP"
"1","(-3325,2975)","0","mstr_standard","I217";
;
CDS_LIB"mstr_standard"
BODY_TYPE"PLUMBING"
HDL_TAP"TRUE";
"B \NAC \NWC"2;
"S \NAC"
BN"23"104;
%"TAP"
"1","(-3325,2875)","0","mstr_standard","I218";
;
CDS_LIB"mstr_standard"
BODY_TYPE"PLUMBING"
HDL_TAP"TRUE";
"B \NAC \NWC"2;
"S \NAC"
BN"24"103;
%"TAP"
"1","(-3325,3025)","0","mstr_standard","I219";
;
CDS_LIB"mstr_standard"
BODY_TYPE"PLUMBING"
HDL_TAP"TRUE";
"B \NAC \NWC"2;
"S \NAC"
BN"22"87;
%"TAP"
"1","(-3325,2825)","0","mstr_standard","I220";
;
CDS_LIB"mstr_standard"
BODY_TYPE"PLUMBING"
HDL_TAP"TRUE";
"B \NAC \NWC"2;
"S \NAC"
BN"25"102;
%"TAP"
"1","(-3325,2775)","0","mstr_standard","I221";
;
CDS_LIB"mstr_standard"
BODY_TYPE"PLUMBING"
HDL_TAP"TRUE";
"B \NAC \NWC"2;
"S \NAC"
BN"26"101;
%"TAP"
"1","(-3325,2725)","0","mstr_standard","I222";
;
CDS_LIB"mstr_standard"
BODY_TYPE"PLUMBING"
HDL_TAP"TRUE";
"B \NAC \NWC"2;
"S \NAC"
BN"27"100;
%"TAP"
"1","(-3325,2675)","0","mstr_standard","I223";
;
CDS_LIB"mstr_standard"
BODY_TYPE"PLUMBING"
HDL_TAP"TRUE";
"B \NAC \NWC"2;
"S \NAC"
BN"28"99;
%"TAP"
"1","(-3325,2575)","0","mstr_standard","I224";
;
CDS_LIB"mstr_standard"
BODY_TYPE"PLUMBING"
HDL_TAP"TRUE";
"B \NAC \NWC"2;
"S \NAC"
BN"30"92;
%"TAP"
"1","(-3325,2625)","0","mstr_standard","I225";
;
CDS_LIB"mstr_standard"
BODY_TYPE"PLUMBING"
HDL_TAP"TRUE";
"B \NAC \NWC"2;
"S \NAC"
BN"29"98;
%"TAP"
"1","(-3325,2325)","0","mstr_standard","I226";
;
CDS_LIB"mstr_standard"
BODY_TYPE"PLUMBING"
HDL_TAP"TRUE";
"B \NAC \NWC"3;
"S \NAC"
BN"2"95;
%"TAP"
"1","(-3325,2375)","0","mstr_standard","I227";
;
CDS_LIB"mstr_standard"
BODY_TYPE"PLUMBING"
HDL_TAP"TRUE";
"B \NAC \NWC"3;
"S \NAC"
BN"1"96;
%"TAP"
"1","(-3325,2425)","0","mstr_standard","I228";
;
CDS_LIB"mstr_standard"
BODY_TYPE"PLUMBING"
HDL_TAP"TRUE";
"B \NAC \NWC"3;
"S \NAC"
BN"0"97;
%"TAP"
"1","(-3325,2525)","0","mstr_standard","I229";
;
CDS_LIB"mstr_standard"
BODY_TYPE"PLUMBING"
HDL_TAP"TRUE";
"B \NAC \NWC"2;
"S \NAC"
BN"31"90;
%"TAP"
"1","(-3325,2225)","0","mstr_standard","I230";
;
CDS_LIB"mstr_standard"
BODY_TYPE"PLUMBING"
HDL_TAP"TRUE";
"B \NAC \NWC"3;
"S \NAC"
BN"4"93;
%"TAP"
"1","(-3325,2275)","0","mstr_standard","I231";
;
CDS_LIB"mstr_standard"
BODY_TYPE"PLUMBING"
HDL_TAP"TRUE";
"B \NAC \NWC"3;
"S \NAC"
BN"3"94;
%"TAP"
"1","(-3325,2175)","0","mstr_standard","I232";
;
CDS_LIB"mstr_standard"
BODY_TYPE"PLUMBING"
HDL_TAP"TRUE";
"B \NAC \NWC"3;
"S \NAC"
BN"5"91;
%"TAP"
"1","(-3325,2125)","0","mstr_standard","I233";
;
CDS_LIB"mstr_standard"
BODY_TYPE"PLUMBING"
HDL_TAP"TRUE";
"B \NAC \NWC"3;
"S \NAC"
BN"6"89;
%"TAP"
"1","(-3325,2075)","0","mstr_standard","I234";
;
CDS_LIB"mstr_standard"
BODY_TYPE"PLUMBING"
HDL_TAP"TRUE";
"B \NAC \NWC"3;
"S \NAC"
BN"7"88;
%"TAP"
"1","(-3325,1825)","0","mstr_standard","I236";
;
CDS_LIB"mstr_standard"
BODY_TYPE"PLUMBING"
HDL_TAP"TRUE";
"B \NAC \NWC"4;
"S \NAC"
BN"3"86;
%"TAP"
"1","(-3325,1875)","0","mstr_standard","I237";
;
CDS_LIB"mstr_standard"
BODY_TYPE"PLUMBING"
HDL_TAP"TRUE";
"B \NAC \NWC"4;
"S \NAC"
BN"2"79;
%"TAP"
"1","(-3325,1975)","0","mstr_standard","I238";
;
CDS_LIB"mstr_standard"
BODY_TYPE"PLUMBING"
HDL_TAP"TRUE";
"B \NAC \NWC"4;
"S \NAC"
BN"0"81;
%"TAP"
"1","(-3325,1925)","0","mstr_standard","I239";
;
CDS_LIB"mstr_standard"
BODY_TYPE"PLUMBING"
HDL_TAP"TRUE";
"B \NAC \NWC"4;
"S \NAC"
BN"1"80;
%"TAP"
"1","(-3325,1675)","0","mstr_standard","I240";
;
CDS_LIB"mstr_standard"
BODY_TYPE"PLUMBING"
HDL_TAP"TRUE";
"B \NAC \NWC"4;
"S \NAC"
BN"6"83;
%"TAP"
"1","(-3325,1775)","0","mstr_standard","I241";
;
CDS_LIB"mstr_standard"
BODY_TYPE"PLUMBING"
HDL_TAP"TRUE";
"B \NAC \NWC"4;
"S \NAC"
BN"4"85;
%"TAP"
"1","(-3325,1725)","0","mstr_standard","I242";
;
CDS_LIB"mstr_standard"
BODY_TYPE"PLUMBING"
HDL_TAP"TRUE";
"B \NAC \NWC"4;
"S \NAC"
BN"5"84;
%"TAP"
"1","(-3325,1625)","0","mstr_standard","I243";
;
CDS_LIB"mstr_standard"
BODY_TYPE"PLUMBING"
HDL_TAP"TRUE";
"B \NAC \NWC"4;
"S \NAC"
BN"7"82;
%"TAP"
"1","(-5750,6025)","2","mstr_standard","I244";
;
CDS_LIB"mstr_standard"
BODY_TYPE"PLUMBING"
HDL_TAP"TRUE";
"B \NAC \NWC"5;
"S \NAC"
BN"0"60;
%"TAP"
"1","(-5750,5925)","2","mstr_standard","I245";
;
CDS_LIB"mstr_standard"
BODY_TYPE"PLUMBING"
HDL_TAP"TRUE";
"B \NAC \NWC"5;
"S \NAC"
BN"1"77;
%"TAP"
"1","(-5750,5825)","2","mstr_standard","I246";
;
CDS_LIB"mstr_standard"
BODY_TYPE"PLUMBING"
HDL_TAP"TRUE";
"B \NAC \NWC"5;
"S \NAC"
BN"2"75;
%"TAP"
"1","(-5750,5725)","2","mstr_standard","I247";
;
CDS_LIB"mstr_standard"
BODY_TYPE"PLUMBING"
HDL_TAP"TRUE";
"B \NAC \NWC"5;
"S \NAC"
BN"3"73;
%"TAP"
"1","(-5950,5975)","2","mstr_standard","I248";
;
CDS_LIB"mstr_standard"
BODY_TYPE"PLUMBING"
HDL_TAP"TRUE";
"B \NAC \NWC"9;
"S \NAC"
BN"0"65;
%"TAP"
"1","(-5950,5875)","2","mstr_standard","I249";
;
CDS_LIB"mstr_standard"
BODY_TYPE"PLUMBING"
HDL_TAP"TRUE";
"B \NAC \NWC"9;
"S \NAC"
BN"1"64;
%"TAP"
"1","(-5950,5775)","2","mstr_standard","I250";
;
CDS_LIB"mstr_standard"
BODY_TYPE"PLUMBING"
HDL_TAP"TRUE";
"B \NAC \NWC"9;
"S \NAC"
BN"2"63;
%"TAP"
"1","(-5950,5675)","2","mstr_standard","I251";
;
CDS_LIB"mstr_standard"
BODY_TYPE"PLUMBING"
HDL_TAP"TRUE";
"B \NAC \NWC"9;
"S \NAC"
BN"3"62;
%"TAP"
"1","(-5750,5525)","2","mstr_standard","I252";
;
CDS_LIB"mstr_standard"
BODY_TYPE"PLUMBING"
HDL_TAP"TRUE";
"B \NAC \NWC"5;
"S \NAC"
BN"5"70;
%"TAP"
"1","(-5750,5625)","2","mstr_standard","I253";
;
CDS_LIB"mstr_standard"
BODY_TYPE"PLUMBING"
HDL_TAP"TRUE";
"B \NAC \NWC"5;
"S \NAC"
BN"4"71;
%"TAP"
"1","(-5750,5425)","2","mstr_standard","I254";
;
CDS_LIB"mstr_standard"
BODY_TYPE"PLUMBING"
HDL_TAP"TRUE";
"B \NAC \NWC"5;
"S \NAC"
BN"6"69;
%"TAP"
"1","(-5750,5325)","2","mstr_standard","I255";
;
CDS_LIB"mstr_standard"
BODY_TYPE"PLUMBING"
HDL_TAP"TRUE";
"B \NAC \NWC"5;
"S \NAC"
BN"7"68;
%"TAP"
"1","(-5750,5125)","2","mstr_standard","I256";
;
CDS_LIB"mstr_standard"
BODY_TYPE"PLUMBING"
HDL_TAP"TRUE";
"B \NAC \NWC"5;
"S \NAC"
BN"9"66;
%"TAP"
"1","(-5750,5225)","2","mstr_standard","I257";
;
CDS_LIB"mstr_standard"
BODY_TYPE"PLUMBING"
HDL_TAP"TRUE";
"B \NAC \NWC"5;
"S \NAC"
BN"8"67;
%"TAP"
"1","(-5950,5575)","2","mstr_standard","I258";
;
CDS_LIB"mstr_standard"
BODY_TYPE"PLUMBING"
HDL_TAP"TRUE";
"B \NAC \NWC"9;
"S \NAC"
BN"4"61;
%"TAP"
"1","(-5950,5475)","2","mstr_standard","I259";
;
CDS_LIB"mstr_standard"
BODY_TYPE"PLUMBING"
HDL_TAP"TRUE";
"B \NAC \NWC"9;
"S \NAC"
BN"5"78;
%"TAP"
"1","(-5950,5375)","2","mstr_standard","I260";
;
CDS_LIB"mstr_standard"
BODY_TYPE"PLUMBING"
HDL_TAP"TRUE";
"B \NAC \NWC"9;
"S \NAC"
BN"6"76;
%"TAP"
"1","(-5950,5275)","2","mstr_standard","I261";
;
CDS_LIB"mstr_standard"
BODY_TYPE"PLUMBING"
HDL_TAP"TRUE";
"B \NAC \NWC"9;
"S \NAC"
BN"7"74;
%"TAP"
"1","(-5950,5175)","2","mstr_standard","I262";
;
CDS_LIB"mstr_standard"
BODY_TYPE"PLUMBING"
HDL_TAP"TRUE";
"B \NAC \NWC"9;
"S \NAC"
BN"8"72;
%"TAP"
"1","(-5750,4875)","2","mstr_standard","I263";
;
CDS_LIB"mstr_standard"
BODY_TYPE"PLUMBING"
HDL_TAP"TRUE";
"B \NAC \NWC"6;
"S \NAC"
BN"1"51;
%"TAP"
"1","(-5750,4975)","2","mstr_standard","I264";
;
CDS_LIB"mstr_standard"
BODY_TYPE"PLUMBING"
HDL_TAP"TRUE";
"B \NAC \NWC"6;
"S \NAC"
BN"0"53;
%"TAP"
"1","(-5750,4775)","2","mstr_standard","I265";
;
CDS_LIB"mstr_standard"
BODY_TYPE"PLUMBING"
HDL_TAP"TRUE";
"B \NAC \NWC"6;
"S \NAC"
BN"2"49;
%"TAP"
"1","(-5750,4675)","2","mstr_standard","I266";
;
CDS_LIB"mstr_standard"
BODY_TYPE"PLUMBING"
HDL_TAP"TRUE";
"B \NAC \NWC"6;
"S \NAC"
BN"3"47;
%"TAP"
"1","(-5950,5075)","2","mstr_standard","I267";
;
CDS_LIB"mstr_standard"
BODY_TYPE"PLUMBING"
HDL_TAP"TRUE";
"B \NAC \NWC"9;
"S \NAC"
BN"9"55;
%"TAP"
"1","(-5950,4925)","2","mstr_standard","I268";
;
CDS_LIB"mstr_standard"
BODY_TYPE"PLUMBING"
HDL_TAP"TRUE";
"B \NAC \NWC"10;
"S \NAC"
BN"0"59;
%"TAP"
"1","(-5950,4825)","2","mstr_standard","I269";
;
CDS_LIB"mstr_standard"
BODY_TYPE"PLUMBING"
HDL_TAP"TRUE";
"B \NAC \NWC"10;
"S \NAC"
BN"1"58;
%"TAP"
"1","(-5950,4725)","2","mstr_standard","I270";
;
CDS_LIB"mstr_standard"
BODY_TYPE"PLUMBING"
HDL_TAP"TRUE";
"B \NAC \NWC"10;
"S \NAC"
BN"2"57;
%"TAP"
"1","(-5950,4625)","2","mstr_standard","I271";
;
CDS_LIB"mstr_standard"
BODY_TYPE"PLUMBING"
HDL_TAP"TRUE";
"B \NAC \NWC"10;
"S \NAC"
BN"3"56;
%"TAP"
"1","(-5750,4575)","2","mstr_standard","I272";
;
CDS_LIB"mstr_standard"
BODY_TYPE"PLUMBING"
HDL_TAP"TRUE";
"B \NAC \NWC"6;
"S \NAC"
BN"4"45;
%"TAP"
"1","(-5750,4475)","2","mstr_standard","I273";
;
CDS_LIB"mstr_standard"
BODY_TYPE"PLUMBING"
HDL_TAP"TRUE";
"B \NAC \NWC"6;
"S \NAC"
BN"5"44;
%"TAP"
"1","(-5750,4375)","2","mstr_standard","I274";
;
CDS_LIB"mstr_standard"
BODY_TYPE"PLUMBING"
HDL_TAP"TRUE";
"B \NAC \NWC"6;
"S \NAC"
BN"6"43;
%"TAP"
"1","(-5750,4275)","2","mstr_standard","I275";
;
CDS_LIB"mstr_standard"
BODY_TYPE"PLUMBING"
HDL_TAP"TRUE";
"B \NAC \NWC"6;
"S \NAC"
BN"7"42;
%"TAP"
"1","(-5750,4175)","2","mstr_standard","I276";
;
CDS_LIB"mstr_standard"
BODY_TYPE"PLUMBING"
HDL_TAP"TRUE";
"B \NAC \NWC"6;
"S \NAC"
BN"8"41;
%"TAP"
"1","(-5950,4525)","2","mstr_standard","I277";
;
CDS_LIB"mstr_standard"
BODY_TYPE"PLUMBING"
HDL_TAP"TRUE";
"B \NAC \NWC"10;
"S \NAC"
BN"4"54;
%"TAP"
"1","(-5950,4425)","2","mstr_standard","I278";
;
CDS_LIB"mstr_standard"
BODY_TYPE"PLUMBING"
HDL_TAP"TRUE";
"B \NAC \NWC"10;
"S \NAC"
BN"5"52;
%"TAP"
"1","(-5950,4325)","2","mstr_standard","I279";
;
CDS_LIB"mstr_standard"
BODY_TYPE"PLUMBING"
HDL_TAP"TRUE";
"B \NAC \NWC"10;
"S \NAC"
BN"6"50;
%"TAP"
"1","(-5950,4225)","2","mstr_standard","I280";
;
CDS_LIB"mstr_standard"
BODY_TYPE"PLUMBING"
HDL_TAP"TRUE";
"B \NAC \NWC"10;
"S \NAC"
BN"7"48;
%"TAP"
"1","(-5950,4125)","2","mstr_standard","I281";
;
CDS_LIB"mstr_standard"
BODY_TYPE"PLUMBING"
HDL_TAP"TRUE";
"B \NAC \NWC"10;
"S \NAC"
BN"8"46;
%"TAP"
"1","(-5750,4075)","2","mstr_standard","I286";
;
CDS_LIB"mstr_standard"
BODY_TYPE"PLUMBING"
HDL_TAP"TRUE";
"B \NAC \NWC"6;
"S \NAC"
BN"9"25;
%"TAP"
"1","(-5950,3825)","2","mstr_standard","I287";
;
CDS_LIB"mstr_standard"
BODY_TYPE"PLUMBING"
HDL_TAP"TRUE";
"B \NAC \NWC"7;
"S \NAC"
BN"1"38;
%"TAP"
"1","(-5950,4025)","2","mstr_standard","I288";
;
CDS_LIB"mstr_standard"
BODY_TYPE"PLUMBING"
HDL_TAP"TRUE";
"B \NAC \NWC"10;
"S \NAC"
BN"9"33;
%"TAP"
"1","(-5950,3875)","2","mstr_standard","I289";
;
CDS_LIB"mstr_standard"
BODY_TYPE"PLUMBING"
HDL_TAP"TRUE";
"B \NAC \NWC"7;
"S \NAC"
BN"0"40;
%"TAP"
"1","(-5950,3775)","2","mstr_standard","I290";
;
CDS_LIB"mstr_standard"
BODY_TYPE"PLUMBING"
HDL_TAP"TRUE";
"B \NAC \NWC"7;
"S \NAC"
BN"2"36;
%"TAP"
"1","(-5950,3725)","2","mstr_standard","I291";
;
CDS_LIB"mstr_standard"
BODY_TYPE"PLUMBING"
HDL_TAP"TRUE";
"B \NAC \NWC"7;
"S \NAC"
BN"3"34;
%"TAP"
"1","(-5950,3675)","2","mstr_standard","I292";
;
CDS_LIB"mstr_standard"
BODY_TYPE"PLUMBING"
HDL_TAP"TRUE";
"B \NAC \NWC"7;
"S \NAC"
BN"4"32;
%"TAP"
"1","(-5950,3625)","2","mstr_standard","I293";
;
CDS_LIB"mstr_standard"
BODY_TYPE"PLUMBING"
HDL_TAP"TRUE";
"B \NAC \NWC"7;
"S \NAC"
BN"5"30;
%"TAP"
"1","(-5950,3575)","2","mstr_standard","I294";
;
CDS_LIB"mstr_standard"
BODY_TYPE"PLUMBING"
HDL_TAP"TRUE";
"B \NAC \NWC"7;
"S \NAC"
BN"6"28;
%"TAP"
"1","(-5950,3425)","2","mstr_standard","I295";
;
CDS_LIB"mstr_standard"
BODY_TYPE"PLUMBING"
HDL_TAP"TRUE";
"B \NAC \NWC"8;
"S \NAC"
BN"1"37;
%"TAP"
"1","(-5950,3475)","2","mstr_standard","I296";
;
CDS_LIB"mstr_standard"
BODY_TYPE"PLUMBING"
HDL_TAP"TRUE";
"B \NAC \NWC"8;
"S \NAC"
BN"0"39;
%"TAP"
"1","(-5950,3325)","2","mstr_standard","I297";
;
CDS_LIB"mstr_standard"
BODY_TYPE"PLUMBING"
HDL_TAP"TRUE";
"B \NAC \NWC"8;
"S \NAC"
BN"3"26;
%"TAP"
"1","(-5950,3375)","2","mstr_standard","I298";
;
CDS_LIB"mstr_standard"
BODY_TYPE"PLUMBING"
HDL_TAP"TRUE";
"B \NAC \NWC"8;
"S \NAC"
BN"2"35;
%"TAP"
"1","(-5950,3275)","2","mstr_standard","I299";
;
CDS_LIB"mstr_standard"
BODY_TYPE"PLUMBING"
HDL_TAP"TRUE";
"B \NAC \NWC"8;
"S \NAC"
BN"4"31;
%"TAP"
"1","(-5950,3225)","2","mstr_standard","I300";
;
CDS_LIB"mstr_standard"
BODY_TYPE"PLUMBING"
HDL_TAP"TRUE";
"B \NAC \NWC"8;
"S \NAC"
BN"5"29;
%"TAP"
"1","(-5950,3175)","2","mstr_standard","I301";
;
CDS_LIB"mstr_standard"
BODY_TYPE"PLUMBING"
HDL_TAP"TRUE";
"B \NAC \NWC"8;
"S \NAC"
BN"6"27;
%"Q_RES"
"1","(-6875,2175)","0","pure_quanta","I314";
;
LOCATION"R378"
$SEC"1"
CDS_SEC"1"
TOLERANCE"1%"
VALUE"15   "
PART_NUMBER"CS01502FB11"
PACK_TYPE"0402LF"
CDS_LIB"pure_quanta"
WATTAGE"1/16W"
MATERIAL"CHIP";
"B"
$PN"2"13;
"A"
$PN"1"11;
END.
